#ISCELL
  mstr_misc dns *
  *
#ISCELL
  mstr_symbols cad_note *
  *
#ISCELL
  mstr_symbols design_note *
  *
#ISCELL
  mstr_symbols intel_corp_bpage *
  *
#CELL
  mstr_discrete res *
  page247_i1
#CELL
  mstr_discrete res *
  page247_i100
#CELL
  mstr_discrete res *
  page247_i101
#ISCELL
  mstr_symbols p3v3_stby *
  page247_i102
#ISCELL
  mstr_symbols gnd *
  page247_i104
#CELL
  dev_discrete cap_a *
  page247_i105
#CELL
  dev_discrete cap_a *
  page247_i107
#ISCELL
  mstr_symbols gnd *
  page247_i108
#ISCELL
  mstr_symbols p3v3_stby *
  page247_i109
#ISCELL
  mstr_symbols p3v3_stby *
  page247_i111
#CELL
  mstr_discrete res *
  page247_i112
#CELL
  w_hdl tca9517dgkr-gp *
  page247_i118
#ISCELL
  mstr_symbols gnd *
  page247_i119
#ISCELL
  mstr_symbols p3v3_stby *
  page247_i12
#CELL
  w_hdl tca9555pwr-gp *
  page247_i120
#ISCELL
  mstr_symbols gnd *
  page247_i121
#ISCELL
  mstr_standard offpage *
  page247_i122
#ISCELL
  mstr_standard offpage *
  page247_i123
#ISCELL
  mstr_standard offpage *
  page247_i124
#ISCELL
  mstr_standard offpage *
  page247_i125
#ISCELL
  mstr_standard offpage *
  page247_i126
#ISCELL
  mstr_standard offpage *
  page247_i128
#ISCELL
  mstr_symbols gnd *
  page247_i13
#ISCELL
  mstr_standard offpage *
  page247_i138
#ISCELL
  mstr_standard offpage *
  page247_i139
#ISCELL
  mstr_standard offpage *
  page247_i140
#ISCELL
  mstr_standard offpage *
  page247_i141
#ISCELL
  mstr_standard offpage *
  page247_i142
#ISCELL
  mstr_standard offpage *
  page247_i143
#ISCELL
  mstr_standard offpage *
  page247_i144
#ISCELL
  mstr_standard offpage *
  page247_i145
#ISCELL
  mstr_standard offpage *
  page247_i146
#ISCELL
  mstr_standard offpage *
  page247_i147
#ISCELL
  mstr_symbols p3v3_stby *
  page247_i148
#ISCELL
  mstr_symbols gnd *
  page247_i150
#CELL
  dev_discrete cap_a *
  page247_i151
#ISCELL
  mstr_standard offpage *
  page247_i152
#ISCELL
  mstr_standard offpage *
  page247_i153
#ISCELL
  mstr_standard offpage *
  page247_i154
#ISCELL
  mstr_symbols p3v3_stby *
  page247_i156
#CELL
  mstr_discrete diode *
  page247_i157
#CELL
  mstr_discrete diode *
  page247_i158
#CELL
  mstr_discrete res *
  page247_i159
#CELL
  mstr_discrete res *
  page247_i160
#CELL
  mstr_discrete res *
  page247_i161
#CELL
  mstr_discrete res *
  page247_i162
#CELL
  mstr_discrete res *
  page247_i163
#CELL
  mstr_discrete res *
  page247_i164
#CELL
  mstr_discrete res *
  page247_i165
#ISCELL
  mstr_symbols gnd *
  page247_i4
#ISCELL
  mstr_symbols p3v3_stby *
  page247_i6
#ISCELL
  mstr_symbols gnd *
  page247_i7
#ISCELL
  mstr_standard offpage *
  page247_i74
#ISCELL
  mstr_standard offpage *
  page247_i75
#ISCELL
  mstr_standard offpage *
  page247_i79
#ISCELL
  mstr_standard offpage *
  page247_i80
#ISCELL
  mstr_symbols p3v3_stby *
  page247_i83
#ISCELL
  mstr_standard offpage *
  page247_i84
#CELL
  dev_discrete cap_a *
  page247_i85
#ISCELL
  mstr_symbols gnd *
  page247_i86
#CELL
  mstr_discrete res *
  page247_i87
#ISCELL
  mstr_symbols p3v3_stby *
  page247_i88
#CELL
  mstr_memory at24c64 *
  page247_i89
#CELL
  mstr_discrete res *
  page247_i90
#ISCELL
  mstr_symbols gnd *
  page247_i91
#CELL
  mstr_discrete res *
  page247_i92
#ISCELL
  mstr_symbols gnd *
  page247_i93
#CELL
  mstr_discrete res *
  page247_i94
#ISCELL
  mstr_standard offpage *
  page247_i95
#ISCELL
  mstr_standard offpage *
  page247_i96
#CELL
  mstr_discrete res *
  page247_i98
#CELL
  mstr_discrete res *
  page247_i99
